(kicad_pcb
	(version 20260206)
	(generator "pcbnew")
	(generator_version "10.0")
	(general
		(thickness 1.6)
		(legacy_teardrops no)
	)
	(paper "A4")
	(title_block
		(title "netronome-mezz — pcbd0082-001_rev01_jul9_a.brd")
		(comment 1 "Open CloudServer (Microsoft) / footprints 560-570 of 714")
	)
	(layers
		(0 "F.Cu" signal "TOP")
		(4 "In1.Cu" signal "02_GND")
		(6 "In2.Cu" signal "03_SIG")
		(8 "In3.Cu" signal "04_SIG")
		(10 "In4.Cu" signal "05_GND")
		(12 "In5.Cu" signal "06_PWR1")
		(14 "In6.Cu" signal "07_SIG")
		(16 "In7.Cu" signal "08_SIG")
		(18 "In8.Cu" signal "09_GND")
		(2 "B.Cu" signal "BOTTOM")
		(9 "F.Adhes" user "F.Adhesive")
		(11 "B.Adhes" user "B.Adhesive")
		(13 "F.Paste" user "Package Geometry/Pastemask Top")
		(15 "B.Paste" user "Package Geometry/Pastemask Bottom")
		(5 "F.SilkS" user "Ref Des/Silkscreen Top")
		(7 "B.SilkS" user "Ref Des/Silkscreen Bottom")
		(1 "F.Mask" user "Board Geometry/Soldermask Top")
		(3 "B.Mask" user "Board Geometry/Soldermask Bottom")
		(17 "Dwgs.User" user "User.Drawings")
		(19 "Cmts.User" user "User.Comments")
		(21 "Eco1.User" user "User.Eco1")
		(23 "Eco2.User" user "User.Eco2")
		(25 "Edge.Cuts" user "Board Geometry/Outline")
		(27 "Margin" user)
		(31 "F.CrtYd" user "Package Geometry/Place Bound Top")
		(29 "B.CrtYd" user "Package Geometry/Place Bound Bottom")
		(35 "F.Fab" user "Ref Des/Assembly Top")
		(33 "B.Fab" user "Ref Des/Assembly Bottom")
		(45 "User.4" user "COMPVAL_TYPE_BOTTOM")
	)
	(footprint ""
		(layer "B.Cu")
		(at 78.650998 14.256004)
		(property "Reference" "V2_A-RAS"
			(at 0 0 0)
			(layer "B.SilkS")
			(hide yes)
			(effects
				(font
					(size 1.27 1.27)
				)
				(justify mirror)
			)
		)
		(property "Value" ""
			(at 0 0 0)
			(layer "B.Fab")
			(effects
				(font
					(size 1.27 1.27)
				)
				(justify mirror)
			)
		)
		(duplicate_pad_numbers_are_jumpers no)
		(pad "1" thru_hole circle
			(at 0 0 180)
			(size 0.4572 0.4572)
			(drill 0.20574)
			(layers "*.Cu" "*.Mask")
			(remove_unused_layers no)
			(net "DDR0_32A_RAS_L")
			(clearance 0.1143)
			(thermal_gap 0.1143)
		)
	)
	(footprint ""
		(layer "B.Cu")
		(at 63.119 38.735 180)
		(property "Reference" "C47"
			(at 0 0 0)
			(layer "B.SilkS")
			(hide yes)
			(effects
				(font
					(size 1.27 1.27)
				)
				(justify mirror)
			)
		)
		(property "Value" "1000PF"
			(at 0.091846 0.2921 90)
			(unlocked yes)
			(layer "B.Fab")
			(hide yes)
			(effects
				(font
					(size 0.7874 0.5842)
					(thickness 0.2032)
				)
				(justify left mirror)
			)
		)
		(property "Device Type" "CAPC0083"
			(at 0.091846 0.2921 90)
			(unlocked yes)
			(layer "B.Fab")
			(hide yes)
			(effects
				(font
					(size 0.7874 0.5842)
					(thickness 0.2032)
				)
				(justify left mirror)
			)
		)
		(duplicate_pad_numbers_are_jumpers no)
		(fp_poly
			(pts
				(xy -0.635 1.0668) (xy -0.635 -1.0668) (xy 0.635 -1.0668) (xy 0.635 1.0668)
			)
			(stroke
				(width 0)
				(type default)
			)
			(fill no)
			(layer "B.CrtYd")
		)
		(fp_line
			(start 0.254 0.508)
			(end 0.254 -0.508)
			(stroke
				(width 0.0254)
				(type default)
			)
			(layer "B.Fab")
		)
		(fp_line
			(start 0.254 -0.508)
			(end -0.254 -0.508)
			(stroke
				(width 0.0254)
				(type default)
			)
			(layer "B.Fab")
		)
		(fp_line
			(start -0.254 0.508)
			(end 0.254 0.508)
			(stroke
				(width 0.0254)
				(type default)
			)
			(layer "B.Fab")
		)
		(fp_line
			(start -0.254 -0.508)
			(end -0.254 0.508)
			(stroke
				(width 0.0254)
				(type default)
			)
			(layer "B.Fab")
		)
		(pad "1" smd rect
			(at 0 -0.4191)
			(size 0.508 0.5334)
			(layers "B.Cu" "B.Mask" "B.Paste")
			(net "10N2224")
		)
		(pad "2" smd rect
			(at 0 0.4191)
			(size 0.508 0.5334)
			(layers "B.Cu" "B.Mask" "B.Paste")
			(net "GND")
		)
		(zone
			(layer "B.Cu")
			(hatch none 0.5)
			(connect_pads
				(clearance 0)
			)
			(min_thickness 0.25)
			(keepout
				(tracks not_allowed)
				(vias allowed)
				(pads allowed)
				(copperpour not_allowed)
				(footprints allowed)
			)
			(placement
				(enabled no)
				(sheetname "")
			)
			(fill
				(thermal_gap 0.5)
				(thermal_bridge_width 0.5)
				(island_removal_mode 0)
			)
			(polygon
				(pts
					(xy 63.1444 38.7604) (xy 63.1444 38.7096) (xy 63.0936 38.7096) (xy 63.0936 38.7604)
				)
			)
		)
	)
	(footprint ""
		(layer "B.Cu")
		(at 3.556 10.16 90)
		(property "Reference" "R375"
			(at 0 0 90)
			(layer "B.SilkS")
			(hide yes)
			(effects
				(font
					(size 1.27 1.27)
				)
				(justify mirror)
			)
		)
		(property "Value" "4.75K"
			(at 0.148158 1.3462 0)
			(unlocked yes)
			(layer "B.Fab")
			(hide yes)
			(effects
				(font
					(size 1.27 0.9652)
					(thickness 0.000001)
				)
				(justify left mirror)
			)
		)
		(property "Device Type" "REST4024"
			(at 0.148158 1.3462 0)
			(unlocked yes)
			(layer "B.Fab")
			(hide yes)
			(effects
				(font
					(size 1.27 0.9652)
					(thickness 0.000001)
				)
				(justify left mirror)
			)
		)
		(duplicate_pad_numbers_are_jumpers no)
		(fp_poly
			(pts
				(xy -0.635 1.0668) (xy -0.635 -1.0668) (xy 0.635 -1.0668) (xy 0.635 1.0668)
			)
			(stroke
				(width 0)
				(type default)
			)
			(fill no)
			(layer "B.CrtYd")
		)
		(fp_line
			(start 0.254 -0.508)
			(end -0.254 -0.508)
			(stroke
				(width 0.0254)
				(type default)
			)
			(layer "B.Fab")
		)
		(fp_line
			(start -0.254 -0.508)
			(end -0.254 0.508)
			(stroke
				(width 0.0254)
				(type default)
			)
			(layer "B.Fab")
		)
		(fp_line
			(start 0.254 0.508)
			(end 0.254 -0.508)
			(stroke
				(width 0.0254)
				(type default)
			)
			(layer "B.Fab")
		)
		(fp_line
			(start -0.254 0.508)
			(end 0.254 0.508)
			(stroke
				(width 0.0254)
				(type default)
			)
			(layer "B.Fab")
		)
		(pad "1" smd rect
			(at 0 -0.4191 270)
			(size 0.508 0.5334)
			(layers "B.Cu" "B.Mask" "B.Paste")
			(net "13N4347")
		)
		(pad "2" smd rect
			(at 0 0.4191 270)
			(size 0.508 0.5334)
			(layers "B.Cu" "B.Mask" "B.Paste")
			(net "GND")
		)
		(zone
			(layer "B.Cu")
			(hatch none 0.5)
			(connect_pads
				(clearance 0)
			)
			(min_thickness 0.25)
			(keepout
				(tracks not_allowed)
				(vias allowed)
				(pads allowed)
				(copperpour not_allowed)
				(footprints allowed)
			)
			(placement
				(enabled no)
				(sheetname "")
			)
			(fill
				(thermal_gap 0.5)
				(thermal_bridge_width 0.5)
				(island_removal_mode 0)
			)
			(polygon
				(pts
					(xy 3.5306 10.1854) (xy 3.5814 10.1854) (xy 3.5814 10.1346) (xy 3.5306 10.1346)
				)
			)
		)
	)
	(footprint ""
		(layer "B.Cu")
		(at 73.05101 13.456006)
		(property "Reference" "V_A-DQ31"
			(at 0 0 0)
			(layer "B.SilkS")
			(hide yes)
			(effects
				(font
					(size 1.27 1.27)
				)
				(justify mirror)
			)
		)
		(property "Value" ""
			(at 0 0 0)
			(layer "B.Fab")
			(effects
				(font
					(size 1.27 1.27)
				)
				(justify mirror)
			)
		)
		(duplicate_pad_numbers_are_jumpers no)
		(pad "1" thru_hole circle
			(at 0 0 180)
			(size 0.4572 0.4572)
			(drill 0.20574)
			(layers "*.Cu" "*.Mask")
			(remove_unused_layers no)
			(net "DDR0_32A_DQ31")
			(clearance 0.1143)
			(thermal_gap 0.1143)
		)
	)
	(footprint ""
		(layer "B.Cu")
		(at 26.035 11.75512)
		(property "Reference" "R147"
			(at 0.73533 2.08788 270)
			(unlocked yes)
			(layer "B.SilkS")
			(effects
				(font
					(size 0.7874 0.5842)
					(thickness 0.127)
				)
				(justify left mirror)
			)
		)
		(property "Value" "0"
			(at 0.148158 1.3462 270)
			(unlocked yes)
			(layer "B.Fab")
			(hide yes)
			(effects
				(font
					(size 1.27 0.9652)
					(thickness 0.000001)
				)
				(justify left mirror)
			)
		)
		(property "Device Type" "REST1111"
			(at 0.148158 1.3462 270)
			(unlocked yes)
			(layer "B.Fab")
			(hide yes)
			(effects
				(font
					(size 1.27 0.9652)
					(thickness 0.000001)
				)
				(justify left mirror)
			)
		)
		(duplicate_pad_numbers_are_jumpers no)
		(fp_poly
			(pts
				(xy -0.635 1.0668) (xy -0.635 -1.0668) (xy 0.635 -1.0668) (xy 0.635 1.0668)
			)
			(stroke
				(width 0)
				(type default)
			)
			(fill no)
			(layer "B.CrtYd")
		)
		(fp_line
			(start -0.254 -0.508)
			(end -0.254 0.508)
			(stroke
				(width 0.0254)
				(type default)
			)
			(layer "B.Fab")
		)
		(fp_line
			(start -0.254 0.508)
			(end 0.254 0.508)
			(stroke
				(width 0.0254)
				(type default)
			)
			(layer "B.Fab")
		)
		(fp_line
			(start 0.254 -0.508)
			(end -0.254 -0.508)
			(stroke
				(width 0.0254)
				(type default)
			)
			(layer "B.Fab")
		)
		(fp_line
			(start 0.254 0.508)
			(end 0.254 -0.508)
			(stroke
				(width 0.0254)
				(type default)
			)
			(layer "B.Fab")
		)
		(pad "1" smd rect
			(at 0 -0.4191 180)
			(size 0.508 0.5334)
			(layers "B.Cu" "B.Mask" "B.Paste")
			(net "NFP_JTAG_ARM_TDI")
		)
		(pad "2" smd rect
			(at 0 0.4191 180)
			(size 0.508 0.5334)
			(layers "B.Cu" "B.Mask" "B.Paste")
			(net "NFP_JTAG_ARM_TDO")
		)
		(zone
			(layer "B.Cu")
			(hatch none 0.5)
			(connect_pads
				(clearance 0)
			)
			(min_thickness 0.25)
			(keepout
				(tracks not_allowed)
				(vias allowed)
				(pads allowed)
				(copperpour not_allowed)
				(footprints allowed)
			)
			(placement
				(enabled no)
				(sheetname "")
			)
			(fill
				(thermal_gap 0.5)
				(thermal_bridge_width 0.5)
				(island_removal_mode 0)
			)
			(polygon
				(pts
					(xy 26.0096 11.72972) (xy 26.0096 11.78052) (xy 26.0604 11.78052) (xy 26.0604 11.72972)
				)
			)
		)
	)
	(footprint ""
		(layer "B.Cu")
		(at 50.237009 31.541974)
		(property "Reference" "C174"
			(at -0.987679 0.081026 270)
			(unlocked yes)
			(layer "B.SilkS")
			(effects
				(font
					(size 0.7874 0.5842)
					(thickness 0.127)
				)
				(justify mirror)
			)
		)
		(property "Value" ""
			(at 0 0 0)
			(layer "B.Fab")
			(effects
				(font
					(size 1.27 1.27)
				)
				(justify mirror)
			)
		)
		(duplicate_pad_numbers_are_jumpers no)
		(fp_circle
			(center 0 0)
			(end 0.104648 0)
			(stroke
				(width 0.1016)
				(type default)
			)
			(fill no)
			(layer "B.SilkS")
		)
		(fp_poly
			(pts
				(xy 0.381 -0.889) (xy 0.381 0.889) (xy -0.381 0.889) (xy -0.381 -0.889)
			)
			(stroke
				(width 0)
				(type default)
			)
			(fill no)
			(layer "B.CrtYd")
		)
		(fp_line
			(start -0.508 -1.016)
			(end -0.508 1.016)
			(stroke
				(width 0.0254)
				(type default)
			)
			(layer "B.Fab")
		)
		(fp_line
			(start -0.508 1.016)
			(end 0.508 1.016)
			(stroke
				(width 0.0254)
				(type default)
			)
			(layer "B.Fab")
		)
		(fp_line
			(start 0.254 -1.016)
			(end -0.508 -1.016)
			(stroke
				(width 0.0254)
				(type default)
			)
			(layer "B.Fab")
		)
		(fp_line
			(start 0.508 -1.016)
			(end 0.254 -1.016)
			(stroke
				(width 0.0254)
				(type default)
			)
			(layer "B.Fab")
		)
		(fp_line
			(start 0.508 1.016)
			(end 0.508 -1.016)
			(stroke
				(width 0.0254)
				(type default)
			)
			(layer "B.Fab")
		)
		(pad "1" smd custom
			(at 0 -0.500126 180)
			(size 0.127 0.127)
			(layers "B.Cu" "B.Mask" "B.Paste")
			(net "VDD_CORE")
			(options
				(clearance outline)
				(anchor circle)
			)
			(primitives
				(gr_poly
					(pts
						(xy -0.1778 0.254) (xy 0.1778 0.254) (xy 0.254 0.1778) (xy 0.254 -0.1778) (xy 0.1778 -0.254) (xy -0.1778 -0.254)
						(xy -0.254 -0.1778) (xy -0.254 0.1778)
					)
					(width 0)
					(fill yes)
				)
			)
		)
		(pad "2" smd custom
			(at 0 0.500126 180)
			(size 0.127 0.127)
			(layers "B.Cu" "B.Mask" "B.Paste")
			(net "GND")
			(options
				(clearance outline)
				(anchor circle)
			)
			(primitives
				(gr_poly
					(pts
						(xy -0.1778 0.254) (xy 0.1778 0.254) (xy 0.254 0.1778) (xy 0.254 -0.1778) (xy 0.1778 -0.254) (xy -0.1778 -0.254)
						(xy -0.254 -0.1778) (xy -0.254 0.1778)
					)
					(width 0)
					(fill yes)
				)
			)
		)
	)
	(footprint ""
		(layer "B.Cu")
		(at 35.179 44.831)
		(property "Reference" "TP13"
			(at -1.16967 -2.159 270)
			(unlocked yes)
			(layer "B.SilkS")
			(effects
				(font
					(size 0.7874 0.5842)
					(thickness 0.127)
				)
				(justify left mirror)
			)
		)
		(property "Value" "*"
			(at 0.4826 -0.14732 0)
			(unlocked yes)
			(layer "B.Fab")
			(hide yes)
			(effects
				(font
					(size 1.27 0.9652)
					(thickness 0.000001)
				)
				(justify left mirror)
			)
		)
		(property "Device Type" "TP_SMALL"
			(at 0.4826 -0.14732 0)
			(unlocked yes)
			(layer "B.Fab")
			(hide yes)
			(effects
				(font
					(size 1.27 0.9652)
					(thickness 0.000001)
				)
				(justify left mirror)
			)
		)
		(duplicate_pad_numbers_are_jumpers no)
		(fp_line
			(start -0.8636 -0.8636)
			(end 0.8636 -0.8636)
			(stroke
				(width 0.1524)
				(type default)
			)
			(layer "B.SilkS")
		)
		(fp_line
			(start -0.8636 0.8636)
			(end -0.8636 -0.8636)
			(stroke
				(width 0.1524)
				(type default)
			)
			(layer "B.SilkS")
		)
		(fp_line
			(start 0.8636 -0.8636)
			(end 0.8636 0.8636)
			(stroke
				(width 0.1524)
				(type default)
			)
			(layer "B.SilkS")
		)
		(fp_line
			(start 0.8636 0.8636)
			(end -0.8636 0.8636)
			(stroke
				(width 0.1524)
				(type default)
			)
			(layer "B.SilkS")
		)
		(fp_poly
			(pts
				(xy 0.635 -0.635) (xy 0.635 0.635) (xy -0.635 0.635) (xy -0.635 -0.635)
			)
			(stroke
				(width 0)
				(type default)
			)
			(fill no)
			(layer "B.CrtYd")
		)
		(pad "1" smd rect
			(at 0 0 180)
			(size 1.27 1.27)
			(layers "B.Cu" "B.Mask" "B.Paste")
			(net "DEBUG_CPLD_PGRM_JTAG_TDI")
		)
	)
	(footprint ""
		(layer "B.Cu")
		(at 33.274 44.831)
		(property "Reference" "TP10"
			(at 0.127 -3.02133 0)
			(unlocked yes)
			(layer "B.SilkS")
			(effects
				(font
					(size 0.7874 0.5842)
					(thickness 0.127)
				)
				(justify left mirror)
			)
		)
		(property "Value" "*"
			(at 0.4826 -0.14732 0)
			(unlocked yes)
			(layer "B.Fab")
			(hide yes)
			(effects
				(font
					(size 1.27 0.9652)
					(thickness 0.000001)
				)
				(justify left mirror)
			)
		)
		(property "Device Type" "TP_SMALL"
			(at 0.4826 -0.14732 0)
			(unlocked yes)
			(layer "B.Fab")
			(hide yes)
			(effects
				(font
					(size 1.27 0.9652)
					(thickness 0.000001)
				)
				(justify left mirror)
			)
		)
		(duplicate_pad_numbers_are_jumpers no)
		(fp_line
			(start -0.8636 -0.8636)
			(end 0.8636 -0.8636)
			(stroke
				(width 0.1524)
				(type default)
			)
			(layer "B.SilkS")
		)
		(fp_line
			(start -0.8636 0.8636)
			(end -0.8636 -0.8636)
			(stroke
				(width 0.1524)
				(type default)
			)
			(layer "B.SilkS")
		)
		(fp_line
			(start 0.8636 -0.8636)
			(end 0.8636 0.8636)
			(stroke
				(width 0.1524)
				(type default)
			)
			(layer "B.SilkS")
		)
		(fp_line
			(start 0.8636 0.8636)
			(end -0.8636 0.8636)
			(stroke
				(width 0.1524)
				(type default)
			)
			(layer "B.SilkS")
		)
		(fp_poly
			(pts
				(xy 0.635 -0.635) (xy 0.635 0.635) (xy -0.635 0.635) (xy -0.635 -0.635)
			)
			(stroke
				(width 0)
				(type default)
			)
			(fill no)
			(layer "B.CrtYd")
		)
		(pad "1" smd rect
			(at 0 0 180)
			(size 1.27 1.27)
			(layers "B.Cu" "B.Mask" "B.Paste")
			(net "DEBUG_CPLD_PGRM_JTAG_TCK")
		)
	)
	(footprint ""
		(layer "B.Cu")
		(at 75.451005 30.612994)
		(property "Reference" "V_A-CB4"
			(at 0 0 0)
			(layer "B.SilkS")
			(hide yes)
			(effects
				(font
					(size 1.27 1.27)
				)
				(justify mirror)
			)
		)
		(property "Value" ""
			(at 0 0 0)
			(layer "B.Fab")
			(effects
				(font
					(size 1.27 1.27)
				)
				(justify mirror)
			)
		)
		(duplicate_pad_numbers_are_jumpers no)
		(pad "1" thru_hole circle
			(at 0 0 180)
			(size 0.4572 0.4572)
			(drill 0.20574)
			(layers "*.Cu" "*.Mask")
			(remove_unused_layers no)
			(net "DDR0_32A_CB4")
			(clearance 0.1143)
			(thermal_gap 0.1143)
		)
	)
	(footprint ""
		(layer "B.Cu")
		(at 31.877 22.225)
		(property "Reference" "R49"
			(at 0 0 0)
			(layer "B.SilkS")
			(hide yes)
			(effects
				(font
					(size 1.27 1.27)
				)
				(justify mirror)
			)
		)
		(property "Value" "4.75K"
			(at 0.148158 1.3462 270)
			(unlocked yes)
			(layer "B.Fab")
			(hide yes)
			(effects
				(font
					(size 1.27 0.9652)
					(thickness 0.000001)
				)
				(justify left mirror)
			)
		)
		(property "Device Type" "REST4024"
			(at 0.148158 1.3462 270)
			(unlocked yes)
			(layer "B.Fab")
			(hide yes)
			(effects
				(font
					(size 1.27 0.9652)
					(thickness 0.000001)
				)
				(justify left mirror)
			)
		)
		(duplicate_pad_numbers_are_jumpers no)
		(fp_poly
			(pts
				(xy -0.635 1.0668) (xy -0.635 -1.0668) (xy 0.635 -1.0668) (xy 0.635 1.0668)
			)
			(stroke
				(width 0)
				(type default)
			)
			(fill no)
			(layer "B.CrtYd")
		)
		(fp_line
			(start -0.254 -0.508)
			(end -0.254 0.508)
			(stroke
				(width 0.0254)
				(type default)
			)
			(layer "B.Fab")
		)
		(fp_line
			(start -0.254 0.508)
			(end 0.254 0.508)
			(stroke
				(width 0.0254)
				(type default)
			)
			(layer "B.Fab")
		)
		(fp_line
			(start 0.254 -0.508)
			(end -0.254 -0.508)
			(stroke
				(width 0.0254)
				(type default)
			)
			(layer "B.Fab")
		)
		(fp_line
			(start 0.254 0.508)
			(end 0.254 -0.508)
			(stroke
				(width 0.0254)
				(type default)
			)
			(layer "B.Fab")
		)
		(pad "1" smd rect
			(at 0 -0.4191 180)
			(size 0.508 0.5334)
			(layers "B.Cu" "B.Mask" "B.Paste")
			(net "CPLD_VERSION_0")
		)
		(pad "2" smd rect
			(at 0 0.4191 180)
			(size 0.508 0.5334)
			(layers "B.Cu" "B.Mask" "B.Paste")
			(net "GND")
		)
		(zone
			(layer "B.Cu")
			(hatch none 0.5)
			(connect_pads
				(clearance 0)
			)
			(min_thickness 0.25)
			(keepout
				(tracks not_allowed)
				(vias allowed)
				(pads allowed)
				(copperpour not_allowed)
				(footprints allowed)
			)
			(placement
				(enabled no)
				(sheetname "")
			)
			(fill
				(thermal_gap 0.5)
				(thermal_bridge_width 0.5)
				(island_removal_mode 0)
			)
			(polygon
				(pts
					(xy 31.8516 22.1996) (xy 31.8516 22.2504) (xy 31.9024 22.2504) (xy 31.9024 22.1996)
				)
			)
		)
	)
	(footprint ""
		(layer "B.Cu")
		(at 54.737 27.8892 180)
		(property "Reference" "C3"
			(at 1.04267 0.7112 270)
			(unlocked yes)
			(layer "B.SilkS")
			(effects
				(font
					(size 0.7874 0.5842)
					(thickness 0.127)
				)
				(justify left mirror)
			)
		)
		(property "Value" "22UF"
			(at 0.148158 1.7526 90)
			(unlocked yes)
			(layer "B.Fab")
			(hide yes)
			(effects
				(font
					(size 1.27 0.9652)
					(thickness 0.000001)
				)
				(justify left mirror)
			)
		)
		(property "Device Type" "CAPC0063"
			(at 0.148158 1.7526 90)
			(unlocked yes)
			(layer "B.Fab")
			(hide yes)
			(effects
				(font
					(size 1.27 0.9652)
					(thickness 0.000001)
				)
				(justify left mirror)
			)
		)
		(duplicate_pad_numbers_are_jumpers no)
		(fp_circle
			(center 0 0)
			(end -0.127 0)
			(stroke
				(width 0.2032)
				(type default)
			)
			(fill no)
			(layer "B.SilkS")
		)
		(fp_poly
			(pts
				(xy -0.7874 -1.6637) (xy 0.7874 -1.6637) (xy 0.7874 1.6637) (xy -0.7874 1.6637)
			)
			(stroke
				(width 0)
				(type default)
			)
			(fill no)
			(layer "B.CrtYd")
		)
		(fp_line
			(start 0.4064 0.8128)
			(end 0.4064 -0.7874)
			(stroke
				(width 0.0254)
				(type default)
			)
			(layer "B.Fab")
		)
		(fp_line
			(start 0.4064 -0.7874)
			(end -0.4064 -0.7874)
			(stroke
				(width 0.0254)
				(type default)
			)
			(layer "B.Fab")
		)
		(fp_line
			(start -0.4064 0.8128)
			(end 0.4064 0.8128)
			(stroke
				(width 0.0254)
				(type default)
			)
			(layer "B.Fab")
		)
		(fp_line
			(start -0.4064 -0.7874)
			(end -0.4064 0.8128)
			(stroke
				(width 0.0254)
				(type default)
			)
			(layer "B.Fab")
		)
		(pad "1" smd rect
			(at 0 -0.8001)
			(size 0.8636 0.9652)
			(layers "B.Cu" "B.Mask" "B.Paste")
			(net "VDD_CORE")
		)
		(pad "2" smd rect
			(at 0 0.8001)
			(size 0.8636 0.9652)
			(layers "B.Cu" "B.Mask" "B.Paste")
			(net "GND")
		)
		(zone
			(layer "B.Cu")
			(hatch none 0.5)
			(connect_pads
				(clearance 0)
			)
			(min_thickness 0.25)
			(keepout
				(tracks not_allowed)
				(vias allowed)
				(pads allowed)
				(copperpour not_allowed)
				(footprints allowed)
			)
			(placement
				(enabled no)
				(sheetname "")
			)
			(fill
				(thermal_gap 0.5)
				(thermal_bridge_width 0.5)
				(island_removal_mode 0)
			)
			(polygon
				(pts
					(xy 54.6735 28.1432) (xy 54.8005 28.1432) (xy 54.8005 27.6352) (xy 54.6735 27.6352)
				)
			)
		)
	)
)
